# BASEBOARD_FAB2 (Tioga Pass) — schematic netlist excerpt (pin names and nets, part order shuffled) for the footprints in the layout excerpt that follows; sources: Cadence DE-HDL packaged netlist, KiCad conversion of Wiwynn_Tioga_Pass_MB.brd

R9F64  RES  0.0 5% CHIP  pkg 0402  page 181 : A = SP2_BMC_CM_UART_TX_R1 ; B = SPA_MID_DBG_RX_R
R4E10  RES  100.0 1% EMPTY  pkg 0402  page 201 : A = PVCCIO_CPU0 ; B = SVID_DIO0_CPU0_R
C2A9  CAP_A  47UF 4V 20% X5R  pkg 0603V  page 228 : A = PVDDQ_KLM ; B = GND

(kicad_pcb
	(version 20260206)
	(generator "pcbnew")
	(generator_version "10.0")
	(general
		(thickness 1.6)
		(legacy_teardrops no)
	)
	(paper "A4")
	(title_block
		(title "Wiwynn_Tioga_Pass_MB.brd")
		(comment 1 "Tioga Pass / footprints 406-408 of 4770")
	)
	(layers
		(0 "F.Cu" signal "TOP")
		(4 "In1.Cu" signal "L2GND")
		(6 "In2.Cu" signal "L3")
		(8 "In3.Cu" signal "L4GND")
		(10 "In4.Cu" signal "L5")
		(12 "In5.Cu" signal "L6GND")
		(14 "In6.Cu" signal "L7VCC")
		(16 "In7.Cu" signal "L8VCC")
		(18 "In8.Cu" signal "L9GND")
		(20 "In9.Cu" signal "L10")
		(22 "In10.Cu" signal "L11GND")
		(24 "In11.Cu" signal "L12")
		(26 "In12.Cu" signal "L13GND")
		(2 "B.Cu" signal "BOTTOM")
		(9 "F.Adhes" user "F.Adhesive")
		(11 "B.Adhes" user "B.Adhesive")
		(13 "F.Paste" user "Package Geometry/Pastemask Top")
		(15 "B.Paste" user "Package Geometry/Pastemask Bottom")
		(5 "F.SilkS" user "Ref Des/Silkscreen Top")
		(7 "B.SilkS" user "Ref Des/Silkscreen Bottom")
		(1 "F.Mask" user "Board Geometry/Soldermask Top")
		(3 "B.Mask" user "Board Geometry/Soldermask Bottom")
		(17 "Dwgs.User" user "User.Drawings")
		(19 "Cmts.User" user "User.Comments")
		(21 "Eco1.User" user "User.Eco1")
		(23 "Eco2.User" user "User.Eco2")
		(25 "Edge.Cuts" user "Board Geometry/Outline")
		(27 "Margin" user)
		(31 "F.CrtYd" user "Package Geometry/Place Bound Top")
		(29 "B.CrtYd" user "Package Geometry/Place Bound Bottom")
		(35 "F.Fab" user "Ref Des/Assembly Top")
		(33 "B.Fab" user "Ref Des/Assembly Bottom")
	)
	(footprint ""
		(layer "F.Cu")
		(at 80.739488 -140.208 -90)
		(property "Reference" "C2A9"
			(at 1.848866 0.752348 270)
			(unlocked yes)
			(layer "F.SilkS")
			(effects
				(font
					(size 1.27 0.9652)
					(thickness 0.1524)
				)
			)
		)
		(property "Value" ""
			(at 0 0 270)
			(layer "F.Fab")
			(effects
				(font
					(size 1.27 1.27)
				)
			)
		)
		(duplicate_pad_numbers_are_jumpers no)
		(fp_rect
			(start -0.500126 1.598422)
			(end 0.500126 -0.201422)
			(stroke
				(width 0)
				(type default)
			)
			(fill no)
			(layer "F.CrtYd")
		)
		(fp_line
			(start -0.500126 1.598422)
			(end -0.500126 -0.201422)
			(stroke
				(width 0.1)
				(type default)
			)
			(layer "F.Fab")
		)
		(fp_line
			(start 0.500126 1.598422)
			(end -0.500126 1.598422)
			(stroke
				(width 0.1)
				(type default)
			)
			(layer "F.Fab")
		)
		(fp_line
			(start -0.500126 -0.201422)
			(end 0.500126 -0.201422)
			(stroke
				(width 0.1)
				(type default)
			)
			(layer "F.Fab")
		)
		(fp_line
			(start 0.500126 -0.201422)
			(end 0.500126 1.598422)
			(stroke
				(width 0.1)
				(type default)
			)
			(layer "F.Fab")
		)
		(pad "1" smd rect
			(at 0 0 180)
			(size 0.889 0.9906)
			(layers "F.Cu" "F.Mask" "F.Paste")
			(net "PVDDQ_KLM")
		)
		(pad "2" smd rect
			(at 0 1.397 180)
			(size 0.889 0.9906)
			(layers "F.Cu" "F.Mask" "F.Paste")
			(net "GND")
		)
		(zone
			(layer "F.Cu")
			(hatch none 0.5)
			(connect_pads
				(clearance 0)
			)
			(min_thickness 0.25)
			(keepout
				(tracks allowed)
				(vias not_allowed)
				(pads allowed)
				(copperpour not_allowed)
				(footprints allowed)
			)
			(placement
				(enabled no)
				(sheetname "")
			)
			(fill
				(thermal_gap 0.5)
				(thermal_bridge_width 0.5)
				(island_removal_mode 0)
			)
			(polygon
				(pts
					(xy 79.786988 -140.7033) (xy 79.786988 -139.7127) (xy 80.294988 -139.7127) (xy 80.294988 -140.7033)
				)
			)
		)
		(zone
			(layer "F.Cu")
			(hatch none 0.5)
			(connect_pads
				(clearance 0)
			)
			(min_thickness 0.25)
			(keepout
				(tracks not_allowed)
				(vias allowed)
				(pads allowed)
				(copperpour not_allowed)
				(footprints allowed)
			)
			(placement
				(enabled no)
				(sheetname "")
			)
			(fill
				(thermal_gap 0.5)
				(thermal_bridge_width 0.5)
				(island_removal_mode 0)
			)
			(polygon
				(pts
					(xy 79.786988 -140.7033) (xy 79.786988 -139.7127) (xy 80.294988 -139.7127) (xy 80.294988 -140.7033)
				)
			)
		)
	)
	(footprint ""
		(layer "F.Cu")
		(at 183.769 -61.976 180)
		(property "Reference" "R4E10"
			(at 0 0 180)
			(layer "F.SilkS")
			(hide yes)
			(effects
				(font
					(size 1.27 1.27)
				)
			)
		)
		(property "Value" ""
			(at 0 0 180)
			(layer "F.Fab")
			(effects
				(font
					(size 1.27 1.27)
				)
			)
		)
		(duplicate_pad_numbers_are_jumpers no)
		(fp_rect
			(start 0.2794 -0.1016)
			(end -0.2794 0.9906)
			(stroke
				(width 0)
				(type default)
			)
			(fill no)
			(layer "F.CrtYd")
		)
		(fp_line
			(start 0.2794 0.9906)
			(end 0.2794 -0.1016)
			(stroke
				(width 0.1)
				(type default)
			)
			(layer "F.Fab")
		)
		(fp_line
			(start 0.2794 -0.1016)
			(end -0.2794 -0.1016)
			(stroke
				(width 0.1)
				(type default)
			)
			(layer "F.Fab")
		)
		(fp_line
			(start -0.2794 0.9906)
			(end 0.2794 0.9906)
			(stroke
				(width 0.1)
				(type default)
			)
			(layer "F.Fab")
		)
		(fp_line
			(start -0.2794 -0.1016)
			(end -0.2794 0.9906)
			(stroke
				(width 0.1)
				(type default)
			)
			(layer "F.Fab")
		)
		(pad "1" smd rect
			(at 0 0 180)
			(size 0.508 0.508)
			(layers "F.Cu" "F.Mask" "F.Paste")
			(net "PVCCIO_CPU0")
		)
		(pad "2" smd rect
			(at 0 0.889 180)
			(size 0.508 0.508)
			(layers "F.Cu" "F.Mask" "F.Paste")
			(net "SVID_DIO0_CPU0_R")
		)
		(zone
			(layer "F.Cu")
			(hatch none 0.5)
			(connect_pads
				(clearance 0)
			)
			(min_thickness 0.25)
			(keepout
				(tracks allowed)
				(vias not_allowed)
				(pads allowed)
				(copperpour not_allowed)
				(footprints allowed)
			)
			(placement
				(enabled no)
				(sheetname "")
			)
			(fill
				(thermal_gap 0.5)
				(thermal_bridge_width 0.5)
				(island_removal_mode 0)
			)
			(polygon
				(pts
					(xy 183.515 -62.23) (xy 184.023 -62.23) (xy 184.023 -62.611) (xy 183.515 -62.611)
				)
			)
		)
		(zone
			(layer "F.Cu")
			(hatch none 0.5)
			(connect_pads
				(clearance 0)
			)
			(min_thickness 0.25)
			(keepout
				(tracks not_allowed)
				(vias allowed)
				(pads allowed)
				(copperpour not_allowed)
				(footprints allowed)
			)
			(placement
				(enabled no)
				(sheetname "")
			)
			(fill
				(thermal_gap 0.5)
				(thermal_bridge_width 0.5)
				(island_removal_mode 0)
			)
			(polygon
				(pts
					(xy 183.515 -62.23) (xy 184.023 -62.23) (xy 184.023 -62.611) (xy 183.515 -62.611)
				)
			)
		)
	)
	(footprint ""
		(layer "F.Cu")
		(at 487.970576 -30.186376)
		(property "Reference" "R9F64"
			(at 0 0 0)
			(layer "F.SilkS")
			(hide yes)
			(effects
				(font
					(size 1.27 1.27)
				)
			)
		)
		(property "Value" ""
			(at 0 0 0)
			(layer "F.Fab")
			(effects
				(font
					(size 1.27 1.27)
				)
			)
		)
		(duplicate_pad_numbers_are_jumpers no)
		(fp_poly
			(pts
				(xy -0.2794 -0.1016) (xy 0.2794 -0.1016) (xy 0.2794 0.9906) (xy -0.2794 0.9906)
			)
			(stroke
				(width 0)
				(type default)
			)
			(fill no)
			(layer "F.CrtYd")
		)
		(fp_line
			(start -0.2794 -0.1016)
			(end -0.2794 0.9906)
			(stroke
				(width 0.1)
				(type default)
			)
			(layer "F.Fab")
		)
		(fp_line
			(start -0.2794 0.9906)
			(end 0.2794 0.9906)
			(stroke
				(width 0.1)
				(type default)
			)
			(layer "F.Fab")
		)
		(fp_line
			(start 0.2794 -0.1016)
			(end -0.2794 -0.1016)
			(stroke
				(width 0.1)
				(type default)
			)
			(layer "F.Fab")
		)
		(fp_line
			(start 0.2794 0.9906)
			(end 0.2794 -0.1016)
			(stroke
				(width 0.1)
				(type default)
			)
			(layer "F.Fab")
		)
		(pad "1" smd rect
			(at 0 0)
			(size 0.508 0.508)
			(layers "F.Cu" "F.Mask" "F.Paste")
			(net "SP2_BMC_CM_UART_TX_R1")
		)
		(pad "2" smd rect
			(at 0 0.889)
			(size 0.508 0.508)
			(layers "F.Cu" "F.Mask" "F.Paste")
			(net "SPA_MID_DBG_RX_R")
		)
		(zone
			(layer "F.Cu")
			(hatch none 0.5)
			(connect_pads
				(clearance 0)
			)
			(min_thickness 0.25)
			(keepout
				(tracks allowed)
				(vias not_allowed)
				(pads allowed)
				(copperpour not_allowed)
				(footprints allowed)
			)
			(placement
				(enabled no)
				(sheetname "")
			)
			(fill
				(thermal_gap 0.5)
				(thermal_bridge_width 0.5)
				(island_removal_mode 0)
			)
			(polygon
				(pts
					(xy 487.716576 -29.932376) (xy 488.224576 -29.932376) (xy 488.224576 -29.551376) (xy 487.716576 -29.551376)
				)
			)
		)
		(zone
			(layer "F.Cu")
			(hatch none 0.5)
			(connect_pads
				(clearance 0)
			)
			(min_thickness 0.25)
			(keepout
				(tracks not_allowed)
				(vias allowed)
				(pads allowed)
				(copperpour not_allowed)
				(footprints allowed)
			)
			(placement
				(enabled no)
				(sheetname "")
			)
			(fill
				(thermal_gap 0.5)
				(thermal_bridge_width 0.5)
				(island_removal_mode 0)
			)
			(polygon
				(pts
					(xy 487.716576 -29.551376) (xy 488.224576 -29.551376) (xy 488.224576 -29.932376) (xy 487.716576 -29.932376)
				)
			)
		)
	)
)
